FILE_TYPE=LIBRARY_PARTS;
primitive 'NCP380HSNAJAAT1G';
  pin
    '-FLAG':
      PIN_NUMBER='(4)';
      OUTPUT_LOAD='(1.0,-1.0)';
    'IN':
      PIN_NUMBER='(1)';
      PINUSE='POWER';
      NO_LOAD_CHECK='Both';
      NO_IO_CHECK='Both';
      NO_ASSERT_CHECK='TRUE';
      NO_DIR_CHECK='TRUE';
      ALLOW_CONNECT='TRUE';
    'ILIM':
      PIN_NUMBER='(5)';
      INPUT_LOAD='(-0.01,0.01)';
    'OUT':
      PIN_NUMBER='(6)';
      OUTPUT_LOAD='(1.0,-1.0)';
    'EN':
      PIN_NUMBER='(3)';
      INPUT_LOAD='(-0.01,0.01)';
    'GND':
      PIN_NUMBER='(2)';
      PINUSE='POWER';
      NO_LOAD_CHECK='Both';
      NO_IO_CHECK='Both';
      NO_ASSERT_CHECK='TRUE';
      NO_DIR_CHECK='TRUE';
      ALLOW_CONNECT='TRUE';
  end_pin;
  body
    PART_NAME='NCP380HSNAJAAT1G';
    BODY_NAME='NCP380HSNAJAAT1G';
    PHYS_DES_PREFIX='U';
    CLASS='IC';
  end_body;
end_primitive;

END.
